(kicad_pcb
	(version 20260206)
	(generator "pcbnew")
	(generator_version "10.0")
	(general
		(thickness 1.6)
		(legacy_teardrops no)
	)
	(paper "A4")
	(title_block
		(title "03242023_DA0F0TMBIJ0_F0T_Motherboard_J_brd_V01_OCP.brd")
		(comment 1 "Grand Teton / footprints 5112-5117 of 6105")
	)
	(layers
		(0 "F.Cu" signal "TOP")
		(4 "In1.Cu" signal "GND")
		(6 "In2.Cu" signal "IN1")
		(8 "In3.Cu" signal "GND1")
		(10 "In4.Cu" signal "IN2")
		(12 "In5.Cu" signal "GND2")
		(14 "In6.Cu" signal "IN3")
		(16 "In7.Cu" signal "GND3")
		(18 "In8.Cu" signal "VCC")
		(20 "In9.Cu" signal "VCC1")
		(22 "In10.Cu" signal "GND4")
		(24 "In11.Cu" signal "IN4")
		(26 "In12.Cu" signal "GND5")
		(28 "In13.Cu" signal "IN5")
		(30 "In14.Cu" signal "GND6")
		(32 "In15.Cu" signal "IN6")
		(34 "In16.Cu" signal "GND7")
		(2 "B.Cu" signal "BOTTOM")
		(9 "F.Adhes" user "F.Adhesive")
		(11 "B.Adhes" user "B.Adhesive")
		(13 "F.Paste" user "Package Geometry/Pastemask Top")
		(15 "B.Paste" user "Package Geometry/Pastemask Bottom")
		(5 "F.SilkS" user "Ref Des/Silkscreen Top")
		(7 "B.SilkS" user "Ref Des/Silkscreen Bottom")
		(1 "F.Mask" user "Board Geometry/Soldermask Top")
		(3 "B.Mask" user "Board Geometry/Soldermask Bottom")
		(17 "Dwgs.User" user "User.Drawings")
		(19 "Cmts.User" user "User.Comments")
		(21 "Eco1.User" user "User.Eco1")
		(23 "Eco2.User" user "User.Eco2")
		(25 "Edge.Cuts" user "Board Geometry/Outline")
		(27 "Margin" user)
		(31 "F.CrtYd" user "Package Geometry/Place Bound Top")
		(29 "B.CrtYd" user "Package Geometry/Place Bound Bottom")
		(35 "F.Fab" user "Ref Des/Assembly Top")
		(33 "B.Fab" user "Ref Des/Assembly Bottom")
	)
	(footprint ""
		(layer "B.Cu")
		(at 157.02788 -112.486948 180)
		(property "Reference" "R3479"
			(at 0 0 0)
			(layer "B.SilkS")
			(hide yes)
			(effects
				(font
					(size 1.27 1.27)
				)
				(justify mirror)
			)
		)
		(property "Value" ""
			(at 0 0 0)
			(layer "B.Fab")
			(effects
				(font
					(size 1.27 1.27)
				)
				(justify mirror)
			)
		)
		(duplicate_pad_numbers_are_jumpers no)
		(fp_line
			(start 0.7874 0.4064)
			(end 0.7874 -0.4064)
			(stroke
				(width 0.1524)
				(type default)
			)
			(layer "B.SilkS")
		)
		(fp_line
			(start 0.7874 -0.4064)
			(end -0.7874 -0.4064)
			(stroke
				(width 0.1524)
				(type default)
			)
			(layer "B.SilkS")
		)
		(fp_line
			(start -0.7874 0.4064)
			(end 0.7874 0.4064)
			(stroke
				(width 0.1524)
				(type default)
			)
			(layer "B.SilkS")
		)
		(fp_line
			(start -0.7874 -0.4064)
			(end -0.7874 0.4064)
			(stroke
				(width 0.1524)
				(type default)
			)
			(layer "B.SilkS")
		)
		(fp_line
			(start 0.67945 0.3048)
			(end 0.67945 -0.305054)
			(stroke
				(width 0.1)
				(type default)
			)
			(layer "B.Fab")
		)
		(fp_line
			(start 0.67945 -0.305054)
			(end 0.12065 -0.305054)
			(stroke
				(width 0.1)
				(type default)
			)
			(layer "B.Fab")
		)
		(fp_line
			(start 0.12065 0.3048)
			(end 0.67945 0.3048)
			(stroke
				(width 0.1)
				(type default)
			)
			(layer "B.Fab")
		)
		(fp_line
			(start 0.12065 0.2794)
			(end 0.12065 0.3048)
			(stroke
				(width 0.1)
				(type default)
			)
			(layer "B.Fab")
		)
		(fp_line
			(start 0.12065 -0.2794)
			(end -0.12065 -0.2794)
			(stroke
				(width 0.1)
				(type default)
			)
			(layer "B.Fab")
		)
		(fp_line
			(start 0.12065 -0.305054)
			(end 0.12065 -0.2794)
			(stroke
				(width 0.1)
				(type default)
			)
			(layer "B.Fab")
		)
		(fp_line
			(start -0.120396 0.3048)
			(end -0.120396 0.2794)
			(stroke
				(width 0.1)
				(type default)
			)
			(layer "B.Fab")
		)
		(fp_line
			(start -0.120396 0.2794)
			(end 0.12065 0.2794)
			(stroke
				(width 0.1)
				(type default)
			)
			(layer "B.Fab")
		)
		(fp_line
			(start -0.12065 -0.2794)
			(end -0.12065 -0.3048)
			(stroke
				(width 0.1)
				(type default)
			)
			(layer "B.Fab")
		)
		(fp_line
			(start -0.12065 -0.3048)
			(end -0.67945 -0.3048)
			(stroke
				(width 0.1)
				(type default)
			)
			(layer "B.Fab")
		)
		(fp_line
			(start -0.67945 0.3048)
			(end -0.120396 0.3048)
			(stroke
				(width 0.1)
				(type default)
			)
			(layer "B.Fab")
		)
		(fp_line
			(start -0.67945 -0.3048)
			(end -0.67945 0.3048)
			(stroke
				(width 0.1)
				(type default)
			)
			(layer "B.Fab")
		)
		(pad "1" smd circle
			(at 0.40005 0)
			(size 0 0)
			(layers "B.Cu" "B.Mask" "B.Paste")
			(net "GPU_BASE_STBY_EN")
		)
		(pad "2" smd circle
			(at -0.40005 0)
			(size 0 0)
			(layers "B.Cu" "B.Mask" "B.Paste")
			(net "GPU_BASE_STBY_EN_R")
		)
	)
	(footprint ""
		(layer "B.Cu")
		(at 374.00484 -339.602572 -90)
		(property "Reference" "PR143"
			(at 0 0 90)
			(layer "B.SilkS")
			(hide yes)
			(effects
				(font
					(size 1.27 1.27)
				)
				(justify mirror)
			)
		)
		(property "Value" ""
			(at 0 0 90)
			(layer "B.Fab")
			(effects
				(font
					(size 1.27 1.27)
				)
				(justify mirror)
			)
		)
		(duplicate_pad_numbers_are_jumpers no)
		(fp_line
			(start -0.7874 0.4064)
			(end 0.7874 0.4064)
			(stroke
				(width 0.1524)
				(type default)
			)
			(layer "B.SilkS")
		)
		(fp_line
			(start 0.7874 0.4064)
			(end 0.7874 -0.4064)
			(stroke
				(width 0.1524)
				(type default)
			)
			(layer "B.SilkS")
		)
		(fp_line
			(start -0.7874 -0.4064)
			(end -0.7874 0.4064)
			(stroke
				(width 0.1524)
				(type default)
			)
			(layer "B.SilkS")
		)
		(fp_line
			(start 0.7874 -0.4064)
			(end -0.7874 -0.4064)
			(stroke
				(width 0.1524)
				(type default)
			)
			(layer "B.SilkS")
		)
		(fp_line
			(start -0.67945 0.3048)
			(end -0.120396 0.3048)
			(stroke
				(width 0.1)
				(type default)
			)
			(layer "B.Fab")
		)
		(fp_line
			(start -0.120396 0.3048)
			(end -0.120396 0.2794)
			(stroke
				(width 0.1)
				(type default)
			)
			(layer "B.Fab")
		)
		(fp_line
			(start 0.12065 0.3048)
			(end 0.67945 0.3048)
			(stroke
				(width 0.1)
				(type default)
			)
			(layer "B.Fab")
		)
		(fp_line
			(start 0.67945 0.3048)
			(end 0.67945 -0.305054)
			(stroke
				(width 0.1)
				(type default)
			)
			(layer "B.Fab")
		)
		(fp_line
			(start -0.120396 0.2794)
			(end 0.12065 0.2794)
			(stroke
				(width 0.1)
				(type default)
			)
			(layer "B.Fab")
		)
		(fp_line
			(start 0.12065 0.2794)
			(end 0.12065 0.3048)
			(stroke
				(width 0.1)
				(type default)
			)
			(layer "B.Fab")
		)
		(fp_line
			(start -0.12065 -0.2794)
			(end -0.12065 -0.3048)
			(stroke
				(width 0.1)
				(type default)
			)
			(layer "B.Fab")
		)
		(fp_line
			(start 0.12065 -0.2794)
			(end -0.12065 -0.2794)
			(stroke
				(width 0.1)
				(type default)
			)
			(layer "B.Fab")
		)
		(fp_line
			(start -0.67945 -0.3048)
			(end -0.67945 0.3048)
			(stroke
				(width 0.1)
				(type default)
			)
			(layer "B.Fab")
		)
		(fp_line
			(start -0.12065 -0.3048)
			(end -0.67945 -0.3048)
			(stroke
				(width 0.1)
				(type default)
			)
			(layer "B.Fab")
		)
		(fp_line
			(start 0.12065 -0.305054)
			(end 0.12065 -0.2794)
			(stroke
				(width 0.1)
				(type default)
			)
			(layer "B.Fab")
		)
		(fp_line
			(start 0.67945 -0.305054)
			(end 0.12065 -0.305054)
			(stroke
				(width 0.1)
				(type default)
			)
			(layer "B.Fab")
		)
		(pad "1" smd circle
			(at 0.40005 0 90)
			(size 0 0)
			(layers "B.Cu" "B.Mask" "B.Paste")
			(net "PVCCIN_CPU0_VOS5")
		)
		(pad "2" smd circle
			(at -0.40005 0 90)
			(size 0 0)
			(layers "B.Cu" "B.Mask" "B.Paste")
			(net "PVCCIN_CPU0")
		)
	)
	(footprint ""
		(layer "B.Cu")
		(at 284.925262 -365.653066 -90)
		(property "Reference" "PR1325"
			(at 0 0 90)
			(layer "B.SilkS")
			(hide yes)
			(effects
				(font
					(size 1.27 1.27)
				)
				(justify mirror)
			)
		)
		(property "Value" ""
			(at 0 0 90)
			(layer "B.Fab")
			(effects
				(font
					(size 1.27 1.27)
				)
				(justify mirror)
			)
		)
		(duplicate_pad_numbers_are_jumpers no)
		(fp_line
			(start -0.7874 0.4064)
			(end 0.7874 0.4064)
			(stroke
				(width 0.1524)
				(type default)
			)
			(layer "B.SilkS")
		)
		(fp_line
			(start 0.7874 0.4064)
			(end 0.7874 -0.4064)
			(stroke
				(width 0.1524)
				(type default)
			)
			(layer "B.SilkS")
		)
		(fp_line
			(start -0.7874 -0.4064)
			(end -0.7874 0.4064)
			(stroke
				(width 0.1524)
				(type default)
			)
			(layer "B.SilkS")
		)
		(fp_line
			(start 0.7874 -0.4064)
			(end -0.7874 -0.4064)
			(stroke
				(width 0.1524)
				(type default)
			)
			(layer "B.SilkS")
		)
		(fp_line
			(start -0.67945 0.3048)
			(end -0.120396 0.3048)
			(stroke
				(width 0.1)
				(type default)
			)
			(layer "B.Fab")
		)
		(fp_line
			(start -0.120396 0.3048)
			(end -0.120396 0.2794)
			(stroke
				(width 0.1)
				(type default)
			)
			(layer "B.Fab")
		)
		(fp_line
			(start 0.12065 0.3048)
			(end 0.67945 0.3048)
			(stroke
				(width 0.1)
				(type default)
			)
			(layer "B.Fab")
		)
		(fp_line
			(start 0.67945 0.3048)
			(end 0.67945 -0.305054)
			(stroke
				(width 0.1)
				(type default)
			)
			(layer "B.Fab")
		)
		(fp_line
			(start -0.120396 0.2794)
			(end 0.12065 0.2794)
			(stroke
				(width 0.1)
				(type default)
			)
			(layer "B.Fab")
		)
		(fp_line
			(start 0.12065 0.2794)
			(end 0.12065 0.3048)
			(stroke
				(width 0.1)
				(type default)
			)
			(layer "B.Fab")
		)
		(fp_line
			(start -0.12065 -0.2794)
			(end -0.12065 -0.3048)
			(stroke
				(width 0.1)
				(type default)
			)
			(layer "B.Fab")
		)
		(fp_line
			(start 0.12065 -0.2794)
			(end -0.12065 -0.2794)
			(stroke
				(width 0.1)
				(type default)
			)
			(layer "B.Fab")
		)
		(fp_line
			(start -0.67945 -0.3048)
			(end -0.67945 0.3048)
			(stroke
				(width 0.1)
				(type default)
			)
			(layer "B.Fab")
		)
		(fp_line
			(start -0.12065 -0.3048)
			(end -0.67945 -0.3048)
			(stroke
				(width 0.1)
				(type default)
			)
			(layer "B.Fab")
		)
		(fp_line
			(start 0.12065 -0.305054)
			(end 0.12065 -0.2794)
			(stroke
				(width 0.1)
				(type default)
			)
			(layer "B.Fab")
		)
		(fp_line
			(start 0.67945 -0.305054)
			(end 0.12065 -0.305054)
			(stroke
				(width 0.1)
				(type default)
			)
			(layer "B.Fab")
		)
		(pad "1" smd circle
			(at 0.40005 0 90)
			(size 0 0)
			(layers "B.Cu" "B.Mask" "B.Paste")
			(net "PVCCFA_EHV_FIVRA_CPU0_VOS4")
		)
		(pad "2" smd circle
			(at -0.40005 0 90)
			(size 0 0)
			(layers "B.Cu" "B.Mask" "B.Paste")
			(net "PVCCFA_EHV_FIVRA_CPU0")
		)
	)
	(footprint ""
		(layer "B.Cu")
		(at 295.93413 -400.999452 -90)
		(property "Reference" "PR2522"
			(at 0 0 90)
			(layer "B.SilkS")
			(hide yes)
			(effects
				(font
					(size 1.27 1.27)
				)
				(justify mirror)
			)
		)
		(property "Value" ""
			(at 0 0 90)
			(layer "B.Fab")
			(effects
				(font
					(size 1.27 1.27)
				)
				(justify mirror)
			)
		)
		(duplicate_pad_numbers_are_jumpers no)
		(fp_line
			(start -0.7874 0.4064)
			(end 0.7874 0.4064)
			(stroke
				(width 0.1524)
				(type default)
			)
			(layer "B.SilkS")
		)
		(fp_line
			(start 0.7874 0.4064)
			(end 0.7874 -0.4064)
			(stroke
				(width 0.1524)
				(type default)
			)
			(layer "B.SilkS")
		)
		(fp_line
			(start -0.7874 -0.4064)
			(end -0.7874 0.4064)
			(stroke
				(width 0.1524)
				(type default)
			)
			(layer "B.SilkS")
		)
		(fp_line
			(start 0.7874 -0.4064)
			(end -0.7874 -0.4064)
			(stroke
				(width 0.1524)
				(type default)
			)
			(layer "B.SilkS")
		)
		(fp_line
			(start -0.67945 0.3048)
			(end -0.120396 0.3048)
			(stroke
				(width 0.1)
				(type default)
			)
			(layer "B.Fab")
		)
		(fp_line
			(start -0.120396 0.3048)
			(end -0.120396 0.2794)
			(stroke
				(width 0.1)
				(type default)
			)
			(layer "B.Fab")
		)
		(fp_line
			(start 0.12065 0.3048)
			(end 0.67945 0.3048)
			(stroke
				(width 0.1)
				(type default)
			)
			(layer "B.Fab")
		)
		(fp_line
			(start 0.67945 0.3048)
			(end 0.67945 -0.305054)
			(stroke
				(width 0.1)
				(type default)
			)
			(layer "B.Fab")
		)
		(fp_line
			(start -0.120396 0.2794)
			(end 0.12065 0.2794)
			(stroke
				(width 0.1)
				(type default)
			)
			(layer "B.Fab")
		)
		(fp_line
			(start 0.12065 0.2794)
			(end 0.12065 0.3048)
			(stroke
				(width 0.1)
				(type default)
			)
			(layer "B.Fab")
		)
		(fp_line
			(start -0.12065 -0.2794)
			(end -0.12065 -0.3048)
			(stroke
				(width 0.1)
				(type default)
			)
			(layer "B.Fab")
		)
		(fp_line
			(start 0.12065 -0.2794)
			(end -0.12065 -0.2794)
			(stroke
				(width 0.1)
				(type default)
			)
			(layer "B.Fab")
		)
		(fp_line
			(start -0.67945 -0.3048)
			(end -0.67945 0.3048)
			(stroke
				(width 0.1)
				(type default)
			)
			(layer "B.Fab")
		)
		(fp_line
			(start -0.12065 -0.3048)
			(end -0.67945 -0.3048)
			(stroke
				(width 0.1)
				(type default)
			)
			(layer "B.Fab")
		)
		(fp_line
			(start 0.12065 -0.305054)
			(end 0.12065 -0.2794)
			(stroke
				(width 0.1)
				(type default)
			)
			(layer "B.Fab")
		)
		(fp_line
			(start 0.67945 -0.305054)
			(end 0.12065 -0.305054)
			(stroke
				(width 0.1)
				(type default)
			)
			(layer "B.Fab")
		)
		(pad "1" smd circle
			(at 0.40005 0 90)
			(size 0 0)
			(layers "B.Cu" "B.Mask" "B.Paste")
			(net "P12V_HSC_SENSE2_P")
		)
		(pad "2" smd circle
			(at -0.40005 0 90)
			(size 0 0)
			(layers "B.Cu" "B.Mask" "B.Paste")
			(net "P12V_HSC_SENSE2_R3_P")
		)
	)
	(footprint ""
		(layer "B.Cu")
		(at 100.306886 -359.788714 180)
		(property "Reference" "R2551"
			(at 0 0 0)
			(layer "B.SilkS")
			(hide yes)
			(effects
				(font
					(size 1.27 1.27)
				)
				(justify mirror)
			)
		)
		(property "Value" ""
			(at 0 0 0)
			(layer "B.Fab")
			(effects
				(font
					(size 1.27 1.27)
				)
				(justify mirror)
			)
		)
		(duplicate_pad_numbers_are_jumpers no)
		(fp_line
			(start 0.7874 0.4064)
			(end 0.7874 -0.4064)
			(stroke
				(width 0.1524)
				(type default)
			)
			(layer "B.SilkS")
		)
		(fp_line
			(start 0.7874 -0.4064)
			(end -0.7874 -0.4064)
			(stroke
				(width 0.1524)
				(type default)
			)
			(layer "B.SilkS")
		)
		(fp_line
			(start -0.7874 0.4064)
			(end 0.7874 0.4064)
			(stroke
				(width 0.1524)
				(type default)
			)
			(layer "B.SilkS")
		)
		(fp_line
			(start -0.7874 -0.4064)
			(end -0.7874 0.4064)
			(stroke
				(width 0.1524)
				(type default)
			)
			(layer "B.SilkS")
		)
		(fp_line
			(start 0.67945 0.3048)
			(end 0.67945 -0.305054)
			(stroke
				(width 0.1)
				(type default)
			)
			(layer "B.Fab")
		)
		(fp_line
			(start 0.67945 -0.305054)
			(end 0.12065 -0.305054)
			(stroke
				(width 0.1)
				(type default)
			)
			(layer "B.Fab")
		)
		(fp_line
			(start 0.12065 0.3048)
			(end 0.67945 0.3048)
			(stroke
				(width 0.1)
				(type default)
			)
			(layer "B.Fab")
		)
		(fp_line
			(start 0.12065 0.2794)
			(end 0.12065 0.3048)
			(stroke
				(width 0.1)
				(type default)
			)
			(layer "B.Fab")
		)
		(fp_line
			(start 0.12065 -0.2794)
			(end -0.12065 -0.2794)
			(stroke
				(width 0.1)
				(type default)
			)
			(layer "B.Fab")
		)
		(fp_line
			(start 0.12065 -0.305054)
			(end 0.12065 -0.2794)
			(stroke
				(width 0.1)
				(type default)
			)
			(layer "B.Fab")
		)
		(fp_line
			(start -0.120396 0.3048)
			(end -0.120396 0.2794)
			(stroke
				(width 0.1)
				(type default)
			)
			(layer "B.Fab")
		)
		(fp_line
			(start -0.120396 0.2794)
			(end 0.12065 0.2794)
			(stroke
				(width 0.1)
				(type default)
			)
			(layer "B.Fab")
		)
		(fp_line
			(start -0.12065 -0.2794)
			(end -0.12065 -0.3048)
			(stroke
				(width 0.1)
				(type default)
			)
			(layer "B.Fab")
		)
		(fp_line
			(start -0.12065 -0.3048)
			(end -0.67945 -0.3048)
			(stroke
				(width 0.1)
				(type default)
			)
			(layer "B.Fab")
		)
		(fp_line
			(start -0.67945 0.3048)
			(end -0.120396 0.3048)
			(stroke
				(width 0.1)
				(type default)
			)
			(layer "B.Fab")
		)
		(fp_line
			(start -0.67945 -0.3048)
			(end -0.67945 0.3048)
			(stroke
				(width 0.1)
				(type default)
			)
			(layer "B.Fab")
		)
		(pad "1" smd circle
			(at 0.40005 0)
			(size 0 0)
			(layers "B.Cu" "B.Mask" "B.Paste")
			(net "P3V3_AUX")
		)
		(pad "2" smd circle
			(at -0.40005 0)
			(size 0 0)
			(layers "B.Cu" "B.Mask" "B.Paste")
			(net "PWRGD_PVCCFA_EHV_FIVRA_CPU1_R")
		)
	)
	(footprint ""
		(layer "B.Cu")
		(at 238.161322 -130.3909 -90)
		(property "Reference" "R578"
			(at 0 0 90)
			(layer "B.SilkS")
			(hide yes)
			(effects
				(font
					(size 1.27 1.27)
				)
				(justify mirror)
			)
		)
		(property "Value" ""
			(at 0 0 90)
			(layer "B.Fab")
			(effects
				(font
					(size 1.27 1.27)
				)
				(justify mirror)
			)
		)
		(duplicate_pad_numbers_are_jumpers no)
		(fp_line
			(start -0.7874 0.4064)
			(end 0.7874 0.4064)
			(stroke
				(width 0.1524)
				(type default)
			)
			(layer "B.SilkS")
		)
		(fp_line
			(start 0.7874 0.4064)
			(end 0.7874 -0.4064)
			(stroke
				(width 0.1524)
				(type default)
			)
			(layer "B.SilkS")
		)
		(fp_line
			(start -0.7874 -0.4064)
			(end -0.7874 0.4064)
			(stroke
				(width 0.1524)
				(type default)
			)
			(layer "B.SilkS")
		)
		(fp_line
			(start 0.7874 -0.4064)
			(end -0.7874 -0.4064)
			(stroke
				(width 0.1524)
				(type default)
			)
			(layer "B.SilkS")
		)
		(fp_line
			(start -0.67945 0.3048)
			(end -0.120396 0.3048)
			(stroke
				(width 0.1)
				(type default)
			)
			(layer "B.Fab")
		)
		(fp_line
			(start -0.120396 0.3048)
			(end -0.120396 0.2794)
			(stroke
				(width 0.1)
				(type default)
			)
			(layer "B.Fab")
		)
		(fp_line
			(start 0.12065 0.3048)
			(end 0.67945 0.3048)
			(stroke
				(width 0.1)
				(type default)
			)
			(layer "B.Fab")
		)
		(fp_line
			(start 0.67945 0.3048)
			(end 0.67945 -0.305054)
			(stroke
				(width 0.1)
				(type default)
			)
			(layer "B.Fab")
		)
		(fp_line
			(start -0.120396 0.2794)
			(end 0.12065 0.2794)
			(stroke
				(width 0.1)
				(type default)
			)
			(layer "B.Fab")
		)
		(fp_line
			(start 0.12065 0.2794)
			(end 0.12065 0.3048)
			(stroke
				(width 0.1)
				(type default)
			)
			(layer "B.Fab")
		)
		(fp_line
			(start -0.12065 -0.2794)
			(end -0.12065 -0.3048)
			(stroke
				(width 0.1)
				(type default)
			)
			(layer "B.Fab")
		)
		(fp_line
			(start 0.12065 -0.2794)
			(end -0.12065 -0.2794)
			(stroke
				(width 0.1)
				(type default)
			)
			(layer "B.Fab")
		)
		(fp_line
			(start -0.67945 -0.3048)
			(end -0.67945 0.3048)
			(stroke
				(width 0.1)
				(type default)
			)
			(layer "B.Fab")
		)
		(fp_line
			(start -0.12065 -0.3048)
			(end -0.67945 -0.3048)
			(stroke
				(width 0.1)
				(type default)
			)
			(layer "B.Fab")
		)
		(fp_line
			(start 0.12065 -0.305054)
			(end 0.12065 -0.2794)
			(stroke
				(width 0.1)
				(type default)
			)
			(layer "B.Fab")
		)
		(fp_line
			(start 0.67945 -0.305054)
			(end 0.12065 -0.305054)
			(stroke
				(width 0.1)
				(type default)
			)
			(layer "B.Fab")
		)
		(pad "1" smd circle
			(at 0.40005 0 90)
			(size 0 0)
			(layers "B.Cu" "B.Mask" "B.Paste")
			(net "SMB_HOST_3V3AUX_SDA_R4")
		)
		(pad "2" smd circle
			(at -0.40005 0 90)
			(size 0 0)
			(layers "B.Cu" "B.Mask" "B.Paste")
			(net "SMB_HOST_3V3AUX_SDA_R")
		)
	)
)
